#ISCELL
  mstr_misc dns *
  *
#ISCELL
  mstr_misc prelim *
  *
#ISCELL
  mstr_symbols cad_note *
  *
#ISCELL
  mstr_symbols intel_corp_bpage *
  *
#ISCELL
  mstr_symbols pvtt_ghj *
  page229_i10
#CELL
  mstr_discrete res *
  page229_i14
#CELL
  mstr_discrete cap *
  page229_i15
#ISCELL
  mstr_symbols gnd *
  page229_i16
#CELL
  mstr_discrete cap *
  page229_i17
#ISCELL
  mstr_symbols gnd *
  page229_i19
#ISCELL
  mstr_standard offpage *
  page229_i2
#CELL
  mstr_discrete cap *
  page229_i21
#ISCELL
  mstr_symbols gnd *
  page229_i22
#ISCELL
  mstr_symbols gnd *
  page229_i23
#CELL
  mstr_vreg mic5166 *
  page229_i24
#CELL
  mstr_discrete cap *
  page229_i25
#ISCELL
  mstr_symbols gnd *
  page229_i26
#CELL
  mstr_discrete cap *
  page229_i27
#ISCELL
  mstr_symbols gnd *
  page229_i28
#CELL
  mstr_discrete cap *
  page229_i29
#ISCELL
  mstr_symbols pvtt_ghj *
  page229_i3
#ISCELL
  mstr_symbols gnd *
  page229_i30
#CELL
  mstr_discrete res *
  page229_i32
#CELL
  mstr_discrete res *
  page229_i34
#CELL
  mstr_discrete res *
  page229_i35
#CELL
  mstr_discrete cap *
  page229_i36
#ISCELL
  mstr_symbols gnd *
  page229_i37
#ISCELL
  mstr_symbols pvddq_ghj *
  page229_i38
#CELL
  mstr_discrete res *
  page229_i39
#ISCELL
  mstr_standard offpage *
  page229_i41
#ISCELL
  mstr_symbols p3v3 *
  page229_i42
#ISCELL
  mstr_symbols p3v3 *
  page229_i43
#ISCELL
  mstr_symbols gnd *
  page229_i45
#CELL
  mstr_discrete cap *
  page229_i46
#CELL
  dev_discrete cap_a *
  page229_i47
#CELL
  dev_discrete cap_a *
  page229_i48
#CELL
  dev_discrete cap_a *
  page229_i49
#CELL
  mstr_discrete res *
  page229_i51
#CELL
  mstr_discrete res *
  page229_i52
#CELL
  mstr_misc shunt *
  page229_i53
#ISCELL
  mstr_symbols gnd *
  page229_i7
